(kicad_pcb
	(version 20260206)
	(generator "pcbnew")
	(generator_version "10.0")
	(general
		(thickness 1.6)
		(legacy_teardrops no)
	)
	(paper "A4")
	(title_block
		(title "v1-chassis-manager — T6M_CM_d_v01_1031_1645.brd")
		(comment 1 "Open CloudServer (Microsoft) / footprint 1154 of 2512 (U102), pads 1-100 of 100")
	)
	(layers
		(0 "F.Cu" signal "TOP")
		(4 "In1.Cu" signal "GND1")
		(6 "In2.Cu" signal "IN1")
		(8 "In3.Cu" signal "VCC1")
		(10 "In4.Cu" signal "VCC2")
		(12 "In5.Cu" signal "GND2")
		(14 "In6.Cu" signal "IN2")
		(16 "In7.Cu" signal "IN3")
		(18 "In8.Cu" signal "GND3")
		(2 "B.Cu" signal "BOTTOM")
		(9 "F.Adhes" user "F.Adhesive")
		(11 "B.Adhes" user "B.Adhesive")
		(13 "F.Paste" user "Package Geometry/Pastemask Top")
		(15 "B.Paste" user "Package Geometry/Pastemask Bottom")
		(5 "F.SilkS" user "Ref Des/Silkscreen Top")
		(7 "B.SilkS" user "Ref Des/Silkscreen Bottom")
		(1 "F.Mask" user "Board Geometry/Soldermask Top")
		(3 "B.Mask" user "Board Geometry/Soldermask Bottom")
		(17 "Dwgs.User" user "User.Drawings")
		(19 "Cmts.User" user "User.Comments")
		(21 "Eco1.User" user "User.Eco1")
		(23 "Eco2.User" user "User.Eco2")
		(25 "Edge.Cuts" user "Board Geometry/Outline")
		(27 "Margin" user)
		(31 "F.CrtYd" user "Package Geometry/Place Bound Top")
		(29 "B.CrtYd" user "Package Geometry/Place Bound Bottom")
		(35 "F.Fab" user "Ref Des/Assembly Top")
		(33 "B.Fab" user "Ref Des/Assembly Bottom")
	)
	(footprint ""
		(layer "F.Cu")
		(at 176.510442 -120.865646 180)
		(property "Reference" "U102"
			(at 0.566166 -9.43737 0)
			(unlocked yes)
			(layer "F.SilkS")
			(effects
				(font
					(size 0.7874 0.5842)
					(thickness 0.1524)
				)
				(justify left)
			)
		)
		(property "Value" ""
			(at 0 0 180)
			(layer "F.Fab")
			(effects
				(font
					(size 1.27 1.27)
				)
			)
		)
		(duplicate_pad_numbers_are_jumpers no)
		(pad "A1" smd circle
			(at -4.500118 -4.500118 180)
			(size 0.49022 0.49022)
			(layers "F.Cu" "F.Mask" "F.Paste")
			(net "FM_CPLD_NODE1_P5V_EN")
		)
		(pad "A2" smd circle
			(at -3.50012 -4.500118 180)
			(size 0.49022 0.49022)
			(layers "F.Cu" "F.Mask" "F.Paste")
			(net "XDP_CPU_NODE1_PWROK")
		)
		(pad "A3" smd circle
			(at -2.500122 -4.500118 180)
			(size 0.49022 0.49022)
			(layers "F.Cu" "F.Mask" "F.Paste")
			(net "FM_CPLD_NODE1_P1V8_STB_EN")
		)
		(pad "A4" smd circle
			(at -1.500124 -4.500118 180)
			(size 0.49022 0.49022)
			(layers "F.Cu" "F.Mask" "F.Paste")
			(net "FM_CPLD_NODE1_P1V538_BMC_EN")
		)
		(pad "A5" smd circle
			(at -0.499872 -4.500118 180)
			(size 0.49022 0.49022)
			(layers "F.Cu" "F.Mask" "F.Paste")
			(net "FM_CPLD_NODE1_P1V26_BMC_EN")
		)
		(pad "A6" smd circle
			(at 0.499872 -4.500118 180)
			(size 0.49022 0.49022)
			(layers "F.Cu" "F.Mask" "F.Paste")
			(net "FM_CPLD_NODE1_P1V5_SUS_EN")
		)
		(pad "A7" smd circle
			(at 1.500124 -4.500118 180)
			(size 0.49022 0.49022)
			(layers "F.Cu" "F.Mask" "F.Paste")
			(net "FM_CPLD_NODE1_PVDDR_STB_EN")
		)
		(pad "A8" smd circle
			(at 2.500122 -4.500118 180)
			(size 0.49022 0.49022)
			(layers "F.Cu" "F.Mask" "F.Paste")
			(net "TP_FM_CPLD_NODE1_P1V0_STB_EN")
		)
		(pad "A9" smd circle
			(at 3.50012 -4.500118 180)
			(size 0.49022 0.49022)
			(layers "F.Cu" "F.Mask" "F.Paste")
			(net "FM_CPLD_NODE1_P1V05_SUS_EN")
		)
		(pad "A10" smd circle
			(at 4.500118 -4.500118 180)
			(size 0.49022 0.49022)
			(layers "F.Cu" "F.Mask" "F.Paste")
			(net "FM_CPLD_NODE1_P3V3_EN")
		)
		(pad "B1" smd circle
			(at -4.500118 -3.50012 180)
			(size 0.49022 0.49022)
			(layers "F.Cu" "F.Mask" "F.Paste")
			(net "PWRGD_NODE1_P12V_PG")
		)
		(pad "B2" smd circle
			(at -3.50012 -3.50012 180)
			(size 0.49022 0.49022)
			(layers "F.Cu" "F.Mask" "F.Paste")
			(net "FM_CPLD_NODE1_P1V8_EN")
		)
		(pad "B3" smd circle
			(at -2.500122 -3.50012 180)
			(size 0.49022 0.49022)
			(layers "F.Cu" "F.Mask" "F.Paste")
			(net "FM_CPLD_NODE1_P1V5_EN")
		)
		(pad "B4" smd circle
			(at -1.500124 -3.50012 180)
			(size 0.49022 0.49022)
			(layers "F.Cu" "F.Mask" "F.Paste")
			(net "FM_CPLD_NODE1_P1V0_EN")
		)
		(pad "B5" smd circle
			(at -0.499872 -3.50012 180)
			(size 0.49022 0.49022)
			(layers "F.Cu" "F.Mask" "F.Paste")
			(net "FM_CPLD_NODE1_P1V05_EN")
		)
		(pad "B6" smd circle
			(at 0.499872 -3.50012 180)
			(size 0.49022 0.49022)
			(layers "F.Cu" "F.Mask" "F.Paste")
			(net "FM_CPLD_NODE1_PVTT_DDR_EN")
		)
		(pad "B7" smd circle
			(at 1.500124 -3.50012 180)
			(size 0.49022 0.49022)
			(layers "F.Cu" "F.Mask" "F.Paste")
			(net "FM_CPLD_NODE1_PVCCP_EN")
		)
		(pad "B8" smd circle
			(at 2.500122 -3.50012 180)
			(size 0.49022 0.49022)
			(layers "F.Cu" "F.Mask" "F.Paste")
			(net "FM_CPLD_NODE1_CLK_PG")
		)
		(pad "B9" smd circle
			(at 3.50012 -3.50012 180)
			(size 0.49022 0.49022)
			(layers "F.Cu" "F.Mask" "F.Paste")
			(net "FM_CPLD_NODE1_P1V8_SUS_EN")
		)
		(pad "B10" smd circle
			(at 4.500118 -3.50012 180)
			(size 0.49022 0.49022)
			(layers "F.Cu" "F.Mask" "F.Paste")
			(net "FM_CPLD_NODE1_P3V3_SUS_EN")
		)
		(pad "C1" smd circle
			(at -4.500118 -2.500122 180)
			(size 0.49022 0.49022)
			(layers "F.Cu" "F.Mask" "F.Paste")
			(net "FM_CPLD_PCIE_SW_PERST_L")
		)
		(pad "C2" smd circle
			(at -3.50012 -2.500122 180)
			(size 0.49022 0.49022)
			(layers "F.Cu" "F.Mask" "F.Paste")
			(net "PWRGD_NODE1_P5V_STB_PG_CPLD")
		)
		(pad "C3" smd circle
			(at -2.500122 -2.500122 180)
			(size 0.49022 0.49022)
			(layers "F.Cu" "F.Mask" "F.Paste")
			(net "TP_FM_CPLD_NODE1_P3V3_STB_SW_EN")
		)
		(pad "C4" smd circle
			(at -1.500124 -2.500122 180)
			(size 0.49022 0.49022)
			(layers "F.Cu" "F.Mask" "F.Paste")
			(net "TP_FM_CPLD_NODE1_PWR_BTN_BMC")
		)
		(pad "C5" smd circle
			(at -0.499872 -2.500122 180)
			(size 0.49022 0.49022)
			(layers "F.Cu" "F.Mask" "F.Paste")
			(net "FM_CPLD_NODE1_LPCRST_L")
		)
		(pad "C6" smd circle
			(at 0.499872 -2.500122 180)
			(size 0.49022 0.49022)
			(layers "F.Cu" "F.Mask" "F.Paste")
			(net "TP_FM_CPLD_NODE1_SSI_PERST_L")
		)
		(pad "C7" smd circle
			(at 1.500124 -2.500122 180)
			(size 0.49022 0.49022)
			(layers "F.Cu" "F.Mask" "F.Paste")
			(net "CM_STATUS_LED_N")
		)
		(pad "C8" smd circle
			(at 2.500122 -2.500122 180)
			(size 0.49022 0.49022)
			(layers "F.Cu" "F.Mask" "F.Paste")
			(net "FM_CPLD_NODE1_SATA_PERST_L")
		)
		(pad "C9" smd circle
			(at 3.50012 -2.500122 180)
			(size 0.49022 0.49022)
			(layers "F.Cu" "F.Mask" "F.Paste")
			(net "FM_CPLD_NODE1_USB_PERST_L")
		)
		(pad "C10" smd circle
			(at 4.500118 -2.500122 180)
			(size 0.49022 0.49022)
			(layers "F.Cu" "F.Mask" "F.Paste")
			(net "FM_CPLD_NODE1_USB_PONRST_L")
		)
		(pad "D1" smd circle
			(at -4.500118 -1.500124 180)
			(size 0.49022 0.49022)
			(layers "F.Cu" "F.Mask" "F.Paste")
			(net "PWRGD_NODE1_P3V3_STB_PG_CPLD")
		)
		(pad "D2" smd circle
			(at -3.50012 -1.500124 180)
			(size 0.49022 0.49022)
			(layers "F.Cu" "F.Mask" "F.Paste")
			(net "PWRGD_NODE1_P1V8_STB_PG")
		)
		(pad "D3" smd circle
			(at -2.500122 -1.500124 180)
			(size 0.49022 0.49022)
			(layers "F.Cu" "F.Mask" "F.Paste")
			(net "PWRGD_NODE1_P1V538_BMC_PG")
		)
		(pad "D4" smd circle
			(at -1.500124 -1.500124 180)
			(size 0.49022 0.49022)
			(layers "F.Cu" "F.Mask" "F.Paste")
			(net "P3V3_STB_NODE1")
		)
		(pad "D5" smd circle
			(at -0.499872 -1.500124 180)
			(size 0.49022 0.49022)
			(layers "F.Cu" "F.Mask" "F.Paste")
			(net "GND")
		)
		(pad "D6" smd circle
			(at 0.499872 -1.500124 180)
			(size 0.49022 0.49022)
			(layers "F.Cu" "F.Mask" "F.Paste")
			(net "P3V3_STB_NODE1")
		)
		(pad "D7" smd circle
			(at 1.500124 -1.500124 180)
			(size 0.49022 0.49022)
			(layers "F.Cu" "F.Mask" "F.Paste")
			(net "GND")
		)
		(pad "D8" smd circle
			(at 2.500122 -1.500124 180)
			(size 0.49022 0.49022)
			(layers "F.Cu" "F.Mask" "F.Paste")
			(net "FM_CPLD_NODE1_BMC_PERST_L")
		)
		(pad "D9" smd circle
			(at 3.50012 -1.500124 180)
			(size 0.49022 0.49022)
			(layers "F.Cu" "F.Mask" "F.Paste")
			(net "TP_FM_CPLD_NODE1_BMC_EXTRST_L")
		)
		(pad "D10" smd circle
			(at 4.500118 -1.500124 180)
			(size 0.49022 0.49022)
			(layers "F.Cu" "F.Mask" "F.Paste")
			(net "FM_CPLD_NODE1_BMC_SRST_L")
		)
		(pad "E1" smd circle
			(at -4.500118 -0.499872 180)
			(size 0.49022 0.49022)
			(layers "F.Cu" "F.Mask" "F.Paste")
			(net "FM_CPLD_NODE1_PWR_BTN_CPU")
		)
		(pad "E2" smd circle
			(at -3.50012 -0.499872 180)
			(size 0.49022 0.49022)
			(layers "F.Cu" "F.Mask" "F.Paste")
			(net "CLK_33K_CPU_NODE1_SUSCLK")
		)
		(pad "E3" smd circle
			(at -2.500122 -0.499872 180)
			(size 0.49022 0.49022)
			(layers "F.Cu" "F.Mask" "F.Paste")
			(net "PWRGD_NODE1_P1V26_BMC_PG")
		)
		(pad "E4" smd circle
			(at -1.500124 -0.499872 180)
			(size 0.49022 0.49022)
			(layers "F.Cu" "F.Mask" "F.Paste")
			(net "P3V3_STB_NODE1")
		)
		(pad "E5" smd circle
			(at -0.499872 -0.499872 180)
			(size 0.49022 0.49022)
			(layers "F.Cu" "F.Mask" "F.Paste")
			(net "GND")
		)
		(pad "E6" smd circle
			(at 0.499872 -0.499872 180)
			(size 0.49022 0.49022)
			(layers "F.Cu" "F.Mask" "F.Paste")
			(net "GND")
		)
		(pad "E7" smd circle
			(at 1.500124 -0.499872 180)
			(size 0.49022 0.49022)
			(layers "F.Cu" "F.Mask" "F.Paste")
			(net "P3V3_STB_NODE1")
		)
		(pad "E8" smd circle
			(at 2.500122 -0.499872 180)
			(size 0.49022 0.49022)
			(layers "F.Cu" "F.Mask" "F.Paste")
			(net "FM_CPU_NODE1_RSTWARN")
		)
		(pad "E9" smd circle
			(at 3.50012 -0.499872 180)
			(size 0.49022 0.49022)
			(layers "F.Cu" "F.Mask" "F.Paste")
			(net "RST_CPU_NODE1_SRTCRST_L")
		)
		(pad "E10" smd circle
			(at 4.500118 -0.499872 180)
			(size 0.49022 0.49022)
			(layers "F.Cu" "F.Mask" "F.Paste")
			(net "TP_CPLD_NODE1_IO39")
		)
		(pad "F1" smd circle
			(at -4.500118 0.499872 180)
			(size 0.49022 0.49022)
			(layers "F.Cu" "F.Mask" "F.Paste")
			(net "PWRGD_NODE1_P1V5_SUS_PG")
		)
		(pad "F2" smd circle
			(at -3.50012 0.499872 180)
			(size 0.49022 0.49022)
			(layers "F.Cu" "F.Mask" "F.Paste")
			(net "PWRGD_NODE1_PVDDR_STB_PG")
		)
		(pad "F3" smd circle
			(at -2.500122 0.499872 180)
			(size 0.49022 0.49022)
			(layers "F.Cu" "F.Mask" "F.Paste")
			(net "PWRGD_NODE1_P1V0")
		)
		(pad "F4" smd circle
			(at -1.500124 0.499872 180)
			(size 0.49022 0.49022)
			(layers "F.Cu" "F.Mask" "F.Paste")
			(net "P3V3_STB_NODE1")
		)
		(pad "F5" smd circle
			(at -0.499872 0.499872 180)
			(size 0.49022 0.49022)
			(layers "F.Cu" "F.Mask" "F.Paste")
			(net "GND")
		)
		(pad "F6" smd circle
			(at 0.499872 0.499872 180)
			(size 0.49022 0.49022)
			(layers "F.Cu" "F.Mask" "F.Paste")
			(net "GND")
		)
		(pad "F7" smd circle
			(at 1.500124 0.499872 180)
			(size 0.49022 0.49022)
			(layers "F.Cu" "F.Mask" "F.Paste")
			(net "P3V3_STB_NODE1")
		)
		(pad "F8" smd circle
			(at 2.500122 0.499872 180)
			(size 0.49022 0.49022)
			(layers "F.Cu" "F.Mask" "F.Paste")
			(net "CPLD_EXT_RST_N")
		)
		(pad "F9" smd circle
			(at 3.50012 0.499872 180)
			(size 0.49022 0.49022)
			(layers "F.Cu" "F.Mask" "F.Paste")
			(net "FM_CPLD_NODE1_CPU_RSMRST_L")
		)
		(pad "F10" smd circle
			(at 4.500118 0.499872 180)
			(size 0.49022 0.49022)
			(layers "F.Cu" "F.Mask" "F.Paste")
			(net "FM_CPLD_NODE1_SYS_PG")
		)
		(pad "G1" smd circle
			(at -4.500118 1.500124 180)
			(size 0.49022 0.49022)
			(layers "F.Cu" "F.Mask" "F.Paste")
			(net "PWRGD_NODE1_P1V05_SUS_PG")
		)
		(pad "G2" smd circle
			(at -3.50012 1.500124 180)
			(size 0.49022 0.49022)
			(layers "F.Cu" "F.Mask" "F.Paste")
			(net "PWRGD_NODE1_P3V3_PG")
		)
		(pad "G3" smd circle
			(at -2.500122 1.500124 180)
			(size 0.49022 0.49022)
			(layers "F.Cu" "F.Mask" "F.Paste")
			(net "PWRGD_NODE1_P1V05_PG")
		)
		(pad "G4" smd circle
			(at -1.500124 1.500124 180)
			(size 0.49022 0.49022)
			(layers "F.Cu" "F.Mask" "F.Paste")
			(net "P3V3_STB_NODE1")
		)
		(pad "G5" smd circle
			(at -0.499872 1.500124 180)
			(size 0.49022 0.49022)
			(layers "F.Cu" "F.Mask" "F.Paste")
			(net "GND")
		)
		(pad "G6" smd circle
			(at 0.499872 1.500124 180)
			(size 0.49022 0.49022)
			(layers "F.Cu" "F.Mask" "F.Paste")
			(net "P3V3_STB_NODE1")
		)
		(pad "G7" smd circle
			(at 1.500124 1.500124 180)
			(size 0.49022 0.49022)
			(layers "F.Cu" "F.Mask" "F.Paste")
			(net "GND")
		)
		(pad "G8" smd circle
			(at 2.500122 1.500124 180)
			(size 0.49022 0.49022)
			(layers "F.Cu" "F.Mask" "F.Paste")
			(net "FM_CPLD_NODE1_CPU_RESET_L")
		)
		(pad "G9" smd circle
			(at 3.50012 1.500124 180)
			(size 0.49022 0.49022)
			(layers "F.Cu" "F.Mask" "F.Paste")
			(net "FM_NODE1_DDR3_DRAM_POK_L")
		)
		(pad "G10" smd circle
			(at 4.500118 1.500124 180)
			(size 0.49022 0.49022)
			(layers "F.Cu" "F.Mask" "F.Paste")
			(net "FM_NODE1_DDR3_SYSPWRGD_L")
		)
		(pad "H1" smd circle
			(at -4.500118 2.500122 180)
			(size 0.49022 0.49022)
			(layers "F.Cu" "F.Mask" "F.Paste")
			(net "PWRGD_NODE1_PVTT_DDR_PG")
		)
		(pad "H2" smd circle
			(at -3.50012 2.500122 180)
			(size 0.49022 0.49022)
			(layers "F.Cu" "F.Mask" "F.Paste")
			(net "JTAG_CPLD1_TDI")
		)
		(pad "H3" smd circle
			(at -2.500122 2.500122 180)
			(size 0.49022 0.49022)
			(layers "F.Cu" "F.Mask" "F.Paste")
			(net "JTAG_CPLD1_TCK")
		)
		(pad "H4" smd circle
			(at -1.500124 2.500122 180)
			(size 0.49022 0.49022)
			(layers "F.Cu" "F.Mask" "F.Paste")
			(net "PWRGD_NODE1_PVCCP_PG")
		)
		(pad "H5" smd circle
			(at -0.499872 2.500122 180)
			(size 0.49022 0.49022)
			(layers "F.Cu" "F.Mask" "F.Paste")
			(net "CPLD_CPU_THRMTRIP_N")
		)
		(pad "H6" smd circle
			(at 0.499872 2.500122 180)
			(size 0.49022 0.49022)
			(layers "F.Cu" "F.Mask" "F.Paste")
			(net "FM_CPU_NODE1_XDP_PG_RST")
		)
		(pad "H7" smd circle
			(at 1.500124 2.500122 180)
			(size 0.49022 0.49022)
			(layers "F.Cu" "F.Mask" "F.Paste")
			(net "XDP_CPU_NODE1_PWROK_STALL_L")
		)
		(pad "H8" smd circle
			(at 2.500122 2.500122 180)
			(size 0.49022 0.49022)
			(layers "F.Cu" "F.Mask" "F.Paste")
			(net "CPLD_THRMTRIP_LOG_N")
		)
		(pad "H9" smd circle
			(at 3.50012 2.500122 180)
			(size 0.49022 0.49022)
			(layers "F.Cu" "F.Mask" "F.Paste")
			(net "FM_CPLD_NODE1_JTAG_POK_L")
		)
		(pad "H10" smd circle
			(at 4.500118 2.500122 180)
			(size 0.49022 0.49022)
			(layers "F.Cu" "F.Mask" "F.Paste")
			(net "LED_PWR_NODE1_L")
		)
		(pad "J1" smd circle
			(at -4.500118 3.50012 180)
			(size 0.49022 0.49022)
			(layers "F.Cu" "F.Mask" "F.Paste")
			(net "JTAG_CPLD1_TMS")
		)
		(pad "J2" smd circle
			(at -3.50012 3.50012 180)
			(size 0.49022 0.49022)
			(layers "F.Cu" "F.Mask" "F.Paste")
			(net "JTAG_CPLD1_TDO")
		)
		(pad "J3" smd circle
			(at -2.500122 3.50012 180)
			(size 0.49022 0.49022)
			(layers "F.Cu" "F.Mask" "F.Paste")
			(net "CPLD_ROW_EN")
		)
		(pad "J4" smd circle
			(at -1.500124 3.50012 180)
			(size 0.49022 0.49022)
			(layers "F.Cu" "F.Mask" "F.Paste")
			(net "CPLD_ROW_LATCH")
		)
		(pad "J5" smd circle
			(at -0.499872 3.50012 180)
			(size 0.49022 0.49022)
			(layers "F.Cu" "F.Mask" "F.Paste")
			(net "FM_CPU_NODE1_RSTRDY_L")
		)
		(pad "J6" smd circle
			(at 0.499872 3.50012 180)
			(size 0.49022 0.49022)
			(layers "F.Cu" "F.Mask" "F.Paste")
			(net "FM_CPLD_NODE1_DEBUG_MODE")
		)
		(pad "J7" smd circle
			(at 1.500124 3.50012 180)
			(size 0.49022 0.49022)
			(layers "F.Cu" "F.Mask" "F.Paste")
			(net "RST_BTN_NODE1_L")
		)
		(pad "J8" smd circle
			(at 2.500122 3.50012 180)
			(size 0.49022 0.49022)
			(layers "F.Cu" "F.Mask" "F.Paste")
			(net "FM_CPLD_NODE1_PWR_BTN_L")
		)
		(pad "J9" smd circle
			(at 3.50012 3.50012 180)
			(size 0.49022 0.49022)
			(layers "F.Cu" "F.Mask" "F.Paste")
			(net "RST_NODE1_CPU_XDP_RSTIN_L")
		)
		(pad "J10" smd circle
			(at 4.500118 3.50012 180)
			(size 0.49022 0.49022)
			(layers "F.Cu" "F.Mask" "F.Paste")
			(net "LED_CPU_NODE1_CPLD")
		)
		(pad "K1" smd circle
			(at -4.500118 4.500118 180)
			(size 0.49022 0.49022)
			(layers "F.Cu" "F.Mask" "F.Paste")
			(net "SYS_AUTO_POWER_ON_N")
		)
		(pad "K2" smd circle
			(at -3.50012 4.500118 180)
			(size 0.49022 0.49022)
			(layers "F.Cu" "F.Mask" "F.Paste")
			(net "FM_NODE1_CORE0_1_RST_L")
		)
		(pad "K3" smd circle
			(at -2.500122 4.500118 180)
			(size 0.49022 0.49022)
			(layers "F.Cu" "F.Mask" "F.Paste")
			(net "FM_CPLD_NODE1_WDT")
		)
		(pad "K4" smd circle
			(at -1.500124 4.500118 180)
			(size 0.49022 0.49022)
			(layers "F.Cu" "F.Mask" "F.Paste")
			(net "FM_CPU_NODE1_SLPMODE")
		)
		(pad "K5" smd circle
			(at -0.499872 4.500118 180)
			(size 0.49022 0.49022)
			(layers "F.Cu" "F.Mask" "F.Paste")
			(net "FM_CPU_NODE1_SLPRDY_L")
		)
		(pad "K6" smd circle
			(at 0.499872 4.500118 180)
			(size 0.49022 0.49022)
			(layers "F.Cu" "F.Mask" "F.Paste")
			(net "CPLD1_RSV3")
		)
		(pad "K7" smd circle
			(at 1.500124 4.500118 180)
			(size 0.49022 0.49022)
			(layers "F.Cu" "F.Mask" "F.Paste")
			(net "CPLD1_RSV2")
		)
		(pad "K8" smd circle
			(at 2.500122 4.500118 180)
			(size 0.49022 0.49022)
			(layers "F.Cu" "F.Mask" "F.Paste")
			(net "CPLD1_RSV1")
		)
		(pad "K9" smd circle
			(at 3.50012 4.500118 180)
			(size 0.49022 0.49022)
			(layers "F.Cu" "F.Mask" "F.Paste")
			(net "H_CPU_NODE1_VR_HOT_L")
		)
		(pad "K10" smd circle
			(at 4.500118 4.500118 180)
			(size 0.49022 0.49022)
			(layers "F.Cu" "F.Mask" "F.Paste")
			(net "IRQ_LVC3_CPU_NODE1_WAKE_L")
		)
	)
)
